# S9S_MB_2U (Grand Teton) — schematic netlist excerpt (pin names and nets, part order shuffled) for the footprints in the layout excerpt that follows; sources: Cadence DE-HDL packaged netlist, KiCad conversion of 03242023_DA0F0TMBIJ0_F0T_Motherboard_J_brd_V01_OCP.brd

C1870  Q_CAP  0.1UF 25V 10% X7R  pkg 0402  page 167 : A = P2E_MB_BMC_TX_BUF_DP<0> ; B = P2E_MB_BMC_TX_BUF_C_DP<0>
R3306  Q_RES  0 5% CHIP  pkg 0402LF  page 165 : A = OCP_V3_2_PRSNT_ALL_R_N ; B = OCP_V3_2_PRSNT_ALL_R3_N

(kicad_pcb
	(version 20260206)
	(generator "pcbnew")
	(generator_version "10.0")
	(general
		(thickness 1.6)
		(legacy_teardrops no)
	)
	(paper "A4")
	(title_block
		(title "03242023_DA0F0TMBIJ0_F0T_Motherboard_J_brd_V01_OCP.brd")
		(comment 1 "Grand Teton / footprints 2857-2858 of 6105")
	)
	(layers
		(0 "F.Cu" signal "TOP")
		(4 "In1.Cu" signal "GND")
		(6 "In2.Cu" signal "IN1")
		(8 "In3.Cu" signal "GND1")
		(10 "In4.Cu" signal "IN2")
		(12 "In5.Cu" signal "GND2")
		(14 "In6.Cu" signal "IN3")
		(16 "In7.Cu" signal "GND3")
		(18 "In8.Cu" signal "VCC")
		(20 "In9.Cu" signal "VCC1")
		(22 "In10.Cu" signal "GND4")
		(24 "In11.Cu" signal "IN4")
		(26 "In12.Cu" signal "GND5")
		(28 "In13.Cu" signal "IN5")
		(30 "In14.Cu" signal "GND6")
		(32 "In15.Cu" signal "IN6")
		(34 "In16.Cu" signal "GND7")
		(2 "B.Cu" signal "BOTTOM")
		(9 "F.Adhes" user "F.Adhesive")
		(11 "B.Adhes" user "B.Adhesive")
		(13 "F.Paste" user "Package Geometry/Pastemask Top")
		(15 "B.Paste" user "Package Geometry/Pastemask Bottom")
		(5 "F.SilkS" user "Ref Des/Silkscreen Top")
		(7 "B.SilkS" user "Ref Des/Silkscreen Bottom")
		(1 "F.Mask" user "Board Geometry/Soldermask Top")
		(3 "B.Mask" user "Board Geometry/Soldermask Bottom")
		(17 "Dwgs.User" user "User.Drawings")
		(19 "Cmts.User" user "User.Comments")
		(21 "Eco1.User" user "User.Eco1")
		(23 "Eco2.User" user "User.Eco2")
		(25 "Edge.Cuts" user "Board Geometry/Outline")
		(27 "Margin" user)
		(31 "F.CrtYd" user "Package Geometry/Place Bound Top")
		(29 "B.CrtYd" user "Package Geometry/Place Bound Bottom")
		(35 "F.Fab" user "Ref Des/Assembly Top")
		(33 "B.Fab" user "Ref Des/Assembly Bottom")
	)
	(footprint ""
		(layer "F.Cu")
		(at 140.70838 -34.994596 180)
		(property "Reference" "R3306"
			(at 0 0 180)
			(layer "F.SilkS")
			(hide yes)
			(effects
				(font
					(size 1.27 1.27)
				)
			)
		)
		(property "Value" ""
			(at 0 0 180)
			(layer "F.Fab")
			(effects
				(font
					(size 1.27 1.27)
				)
			)
		)
		(duplicate_pad_numbers_are_jumpers no)
		(fp_line
			(start 0.7874 0.4064)
			(end -0.7874 0.4064)
			(stroke
				(width 0.1524)
				(type default)
			)
			(layer "F.SilkS")
		)
		(fp_line
			(start 0.7874 -0.4064)
			(end 0.7874 0.4064)
			(stroke
				(width 0.1524)
				(type default)
			)
			(layer "F.SilkS")
		)
		(fp_line
			(start -0.7874 0.4064)
			(end -0.7874 -0.4064)
			(stroke
				(width 0.1524)
				(type default)
			)
			(layer "F.SilkS")
		)
		(fp_line
			(start -0.7874 -0.4064)
			(end 0.7874 -0.4064)
			(stroke
				(width 0.1524)
				(type default)
			)
			(layer "F.SilkS")
		)
		(fp_line
			(start 0.67945 0.3048)
			(end 0.120396 0.3048)
			(stroke
				(width 0.1)
				(type default)
			)
			(layer "F.Fab")
		)
		(fp_line
			(start 0.67945 -0.3048)
			(end 0.67945 0.3048)
			(stroke
				(width 0.1)
				(type default)
			)
			(layer "F.Fab")
		)
		(fp_line
			(start 0.12065 -0.2794)
			(end 0.12065 -0.3048)
			(stroke
				(width 0.1)
				(type default)
			)
			(layer "F.Fab")
		)
		(fp_line
			(start 0.12065 -0.3048)
			(end 0.67945 -0.3048)
			(stroke
				(width 0.1)
				(type default)
			)
			(layer "F.Fab")
		)
		(fp_line
			(start 0.120396 0.3048)
			(end 0.120396 0.2794)
			(stroke
				(width 0.1)
				(type default)
			)
			(layer "F.Fab")
		)
		(fp_line
			(start 0.120396 0.2794)
			(end -0.12065 0.2794)
			(stroke
				(width 0.1)
				(type default)
			)
			(layer "F.Fab")
		)
		(fp_line
			(start -0.12065 0.3048)
			(end -0.67945 0.3048)
			(stroke
				(width 0.1)
				(type default)
			)
			(layer "F.Fab")
		)
		(fp_line
			(start -0.12065 0.2794)
			(end -0.12065 0.3048)
			(stroke
				(width 0.1)
				(type default)
			)
			(layer "F.Fab")
		)
		(fp_line
			(start -0.12065 -0.2794)
			(end 0.12065 -0.2794)
			(stroke
				(width 0.1)
				(type default)
			)
			(layer "F.Fab")
		)
		(fp_line
			(start -0.12065 -0.305054)
			(end -0.12065 -0.2794)
			(stroke
				(width 0.1)
				(type default)
			)
			(layer "F.Fab")
		)
		(fp_line
			(start -0.67945 0.3048)
			(end -0.67945 -0.305054)
			(stroke
				(width 0.1)
				(type default)
			)
			(layer "F.Fab")
		)
		(fp_line
			(start -0.67945 -0.305054)
			(end -0.12065 -0.305054)
			(stroke
				(width 0.1)
				(type default)
			)
			(layer "F.Fab")
		)
		(pad "1" smd circle
			(at -0.40005 0 180)
			(size 0 0)
			(layers "F.Cu" "F.Mask" "F.Paste")
			(net "OCP_V3_2_PRSNT_ALL_R_N")
		)
		(pad "2" smd circle
			(at 0.40005 0 180)
			(size 0 0)
			(layers "F.Cu" "F.Mask" "F.Paste")
			(net "OCP_V3_2_PRSNT_ALL_R3_N")
		)
	)
	(footprint ""
		(layer "F.Cu")
		(at 18.640806 -396.010638 90)
		(property "Reference" "C1870"
			(at 0 0 90)
			(layer "F.SilkS")
			(hide yes)
			(effects
				(font
					(size 1.27 1.27)
				)
			)
		)
		(property "Value" ""
			(at 0 0 90)
			(layer "F.Fab")
			(effects
				(font
					(size 1.27 1.27)
				)
			)
		)
		(duplicate_pad_numbers_are_jumpers no)
		(fp_line
			(start 0.7874 -0.4064)
			(end 0.7874 0.4064)
			(stroke
				(width 0.1524)
				(type default)
			)
			(layer "F.SilkS")
		)
		(fp_line
			(start -0.7874 -0.4064)
			(end 0.7874 -0.4064)
			(stroke
				(width 0.1524)
				(type default)
			)
			(layer "F.SilkS")
		)
		(fp_line
			(start 0.003302 0.4064)
			(end -0.7874 0.4064)
			(stroke
				(width 0.1524)
				(type default)
			)
			(layer "F.SilkS")
		)
		(fp_line
			(start 0.6858 -0.3048)
			(end 0.6858 0.3048)
			(stroke
				(width 0.1)
				(type default)
			)
			(layer "F.Fab")
		)
		(fp_line
			(start 0.1016 -0.3048)
			(end 0.6858 -0.3048)
			(stroke
				(width 0.1)
				(type default)
			)
			(layer "F.Fab")
		)
		(fp_line
			(start -0.1016 -0.3048)
			(end -0.1016 -0.2794)
			(stroke
				(width 0.1)
				(type default)
			)
			(layer "F.Fab")
		)
		(fp_line
			(start -0.6858 -0.3048)
			(end -0.1016 -0.3048)
			(stroke
				(width 0.1)
				(type default)
			)
			(layer "F.Fab")
		)
		(fp_line
			(start 0.1016 -0.2794)
			(end 0.1016 -0.3048)
			(stroke
				(width 0.1)
				(type default)
			)
			(layer "F.Fab")
		)
		(fp_line
			(start -0.1016 -0.2794)
			(end 0.1016 -0.2794)
			(stroke
				(width 0.1)
				(type default)
			)
			(layer "F.Fab")
		)
		(fp_line
			(start 0.1016 0.2794)
			(end -0.1016 0.2794)
			(stroke
				(width 0.1)
				(type default)
			)
			(layer "F.Fab")
		)
		(fp_line
			(start -0.1016 0.2794)
			(end -0.1016 0.3048)
			(stroke
				(width 0.1)
				(type default)
			)
			(layer "F.Fab")
		)
		(fp_line
			(start 0.6858 0.3048)
			(end 0.1016 0.3048)
			(stroke
				(width 0.1)
				(type default)
			)
			(layer "F.Fab")
		)
		(fp_line
			(start 0.1016 0.3048)
			(end 0.1016 0.2794)
			(stroke
				(width 0.1)
				(type default)
			)
			(layer "F.Fab")
		)
		(fp_line
			(start -0.1016 0.3048)
			(end -0.6858 0.3048)
			(stroke
				(width 0.1)
				(type default)
			)
			(layer "F.Fab")
		)
		(fp_line
			(start -0.6858 0.3048)
			(end -0.6858 -0.3048)
			(stroke
				(width 0.1)
				(type default)
			)
			(layer "F.Fab")
		)
		(pad "1" smd rect
			(at -0.40005 0 270)
			(size 0.4572 0.508)
			(layers "F.Cu" "F.Mask" "F.Paste")
			(net "P2E_MB_BMC_TX_BUF_DP<0>")
		)
		(pad "2" smd rect
			(at 0.40005 0 270)
			(size 0.4572 0.508)
			(layers "F.Cu" "F.Mask" "F.Paste")
			(net "P2E_MB_BMC_TX_BUF_C_DP<0>")
		)
	)
)
